# S9S_MB_2U (Grand Teton) — schematic netlist excerpt (pin names and nets, part order shuffled) for the footprints in the layout excerpt that follows; sources: Cadence DE-HDL packaged netlist, KiCad conversion of 03242023_DA0F0TMBIJ0_F0T_Motherboard_J_brd_V01_OCP.brd

J12  SCONN288_ADR50017P087CC  SCONN288_ADR50017-P087CC IO  pkg DDR288S_1-1VXB  page 93
  VIN_BULK0  = P12V_S3_AUX_CPU0_NVDIMM
  RFU0  = TP_CHF_CPU0_DIMM2_FRU_0
  VIN_MGMT  = P3V3_AUX
  HSCL  = I3C_SPD_DDREFGH_CPU0_LVC1_SCL_3
  HSDA  = I3C_SPD_DDREFGH_CPU0_LVC1_SDA
  VSS0  = GND
  DQ0_A  = M_F_CPU0_SA_DQ<0>
  VSS1  = GND
  DQ1_A  = M_F_CPU0_SA_DQ<1>
  VSS2  = GND
  DQS0_A_T  = M_F_CPU0_SA_DQS_DP<0>
  DQS0_A_C  = M_F_CPU0_SA_DQS_DN<0>
  VSS3  = GND
  DQ4_A  = M_F_CPU0_SA_DQ<4>
  VSS4  = GND
  DQ5_A  = M_F_CPU0_SA_DQ<5>
  VSS5  = GND
  DQ8_A  = M_F_CPU0_SA_DQ<8>
  VSS6  = GND
  DQ9_A  = M_F_CPU0_SA_DQ<9>
  VSS7  = GND
  DQS1_A_T  = M_F_CPU0_SA_DQS_DP<1>
  DQS1_A_C  = M_F_CPU0_SA_DQS_DN<1>
  VSS8  = GND
  DQ12_A  = M_F_CPU0_SA_DQ<12>
  VSS9  = GND
  DQ13_A  = M_F_CPU0_SA_DQ<13>
  VSS10  = GND
  DQ16_A  = M_F_CPU0_SA_DQ<16>
  VSS11  = GND
  DQ17_A  = M_F_CPU0_SA_DQ<17>
  VSS12  = GND
  DQS2_A_T  = M_F_CPU0_SA_DQS_DP<2>
  DQS2_A_C  = M_F_CPU0_SA_DQS_DN<2>
  VSS13  = GND
  DQ20_A  = M_F_CPU0_SA_DQ<20>
  VSS14  = GND
  DQ21_A  = M_F_CPU0_SA_DQ<21>
  VSS15  = GND
  DQ24_A  = M_F_CPU0_SA_DQ<24>
  VSS16  = GND
  DQ25_A  = M_F_CPU0_SA_DQ<25>
  VSS17  = GND
  DQS3_A_T  = M_F_CPU0_SA_DQS_DP<3>
  DQS3_A_C  = M_F_CPU0_SA_DQS_DN<3>
  VSS18  = GND
  DQ28_A  = M_F_CPU0_SA_DQ<28>
  VSS19  = GND
  DQ29_A  = M_F_CPU0_SA_DQ<29>
  VSS20  = GND
  CB0_A  = M_F_CPU0_SA_CB<0>
  VSS21  = GND
  CB1_A  = M_F_CPU0_SA_CB<1>
  VSS22  = GND
  DQS4_A_T  = M_F_CPU0_SA_DQS_DP<4>
  DQS4_A_C  = M_F_CPU0_SA_DQS_DN<4>
  VSS23  = GND
  CB4_A  = M_F_CPU0_SA_CB<4>
  VSS24  = GND
  CB5_A  = M_F_CPU0_SA_CB<5>
  VSS25  = GND
  ALERT_N  = M_F_CPU0_ALERT_N
  VSS26  = GND
  CS0_A_N  = M_F_CPU0_SA_CS_N<2>
  VSS27  = GND
  CA0_A  = M_F_CPU0_SA_CA<0>
  VSS28  = GND
  CA2_A  = M_F_CPU0_SA_CA<2>
  VSS29  = GND
  CA4_A  = M_F_CPU0_SA_CA<4>
  VSS30  = GND
  CA6_A  = M_F_CPU0_SA_CA<6>
  VSS31  = GND
  PAR_A  = M_F_CPU0_SA_PAR
  VSS32  = GND
  CA0_B  = M_F_CPU0_SB_CA<0>
  VSS33  = GND
  CA2_B  = M_F_CPU0_SB_CA<2>
  VSS34  = GND
  CA4_B  = M_F_CPU0_SB_CA<4>
  VSS35  = GND
  CA6_B  = M_F_CPU0_SB_CA<6>
  VSS36  = GND
  CS0_B_N  = M_F_CPU0_SB_CS_N<2>
  VSS37  = GND
  \lbd||rsp_a_n\  = M_F_CPU0_SA_RSP<1>
  \lbs||rsp_b_n\  = M_F_CPU0_SB_RSP<1>
  VSS38  = GND
  CB4_B  = M_F_CPU0_SB_CB<4>
  VSS39  = GND
  CB5_B  = M_F_CPU0_SB_CB<5>
  VSS40  = GND
  \dqs9_b_t||tdqs9_b_t||dbi4_b_n\  = M_F_CPU0_SB_DQS_DP<9>
  \dqs9_b_c||tdqs9_b_c\  = M_F_CPU0_SB_DQS_DN<9>
  VSS41  = GND
  CB0_B  = M_F_CPU0_SB_CB<0>
  VSS42  = GND
  CB1_B  = M_F_CPU0_SB_CB<1>
  VSS43  = GND
  DQ0_B  = M_F_CPU0_SB_DQ<0>
  VSS44  = GND
  DQ1_B  = M_F_CPU0_SB_DQ<1>
  VSS45  = GND
  DQS0_B_T  = M_F_CPU0_SB_DQS_DP<0>
  DQS0_B_C  = M_F_CPU0_SB_DQS_DN<0>
  VSS46  = GND
  DQ4_B  = M_F_CPU0_SB_DQ<4>
  VSS47  = GND
  DQ5_B  = M_F_CPU0_SB_DQ<5>
  VSS48  = GND
  DQ8_B  = M_F_CPU0_SB_DQ<8>
  VSS49  = GND
  DQ9_B  = M_F_CPU0_SB_DQ<9>
  VSS50  = GND
  DQS1_B_T  = M_F_CPU0_SB_DQS_DP<1>
  DQS1_B_C  = M_F_CPU0_SB_DQS_DN<1>
  VSS51  = GND
  DQ12_B  = M_F_CPU0_SB_DQ<12>
  VSS52  = GND
  DQ13_B  = M_F_CPU0_SB_DQ<13>
  VSS53  = GND
  DQ16_B  = M_F_CPU0_SB_DQ<16>
  VSS54  = GND
  DQ17_B  = M_F_CPU0_SB_DQ<17>
  VSS55  = GND
  DQS2_B_T  = M_F_CPU0_SB_DQS_DP<2>
  DQS2_B_C  = M_F_CPU0_SB_DQS_DN<2>
  VSS56  = GND
  DQ20_B  = M_F_CPU0_SB_DQ<20>
  VSS57  = GND
  DQ21_B  = M_F_CPU0_SB_DQ<21>
  VSS58  = GND
  DQ24_B  = M_F_CPU0_SB_DQ<24>
  VSS59  = GND
  DQ25_B  = M_F_CPU0_SB_DQ<25>
  VSS60  = GND
  DQS3_B_T  = M_F_CPU0_SB_DQS_DP<3>
  DQS3_B_C  = M_F_CPU0_SB_DQS_DN<3>
  VSS61  = GND
  DQ28_B  = M_F_CPU0_SB_DQ<28>
  VSS62  = GND
  DQ29_B  = M_F_CPU0_SB_DQ<29>
  VSS63  = GND
  RFU1  = TP_CHF_CPU0_DIMM2_FRU_1
  VIN_BULK1  = P12V_S3_AUX_CPU0_NVDIMM
  VIN_BULK2  = P12V_S3_AUX_CPU0_NVDIMM
  \pwr_good||fail_n\  = PWRGD_CHF_CPU0_DIMM2
  HSA  = PD_CHF_CPU0_DIMM2_SAA
  RFU2  = TP_CHF_CPU0_DIMM2_FRU_2
  RFU3  = TP_CHF_CPU0_DIMM2_FRU_3
  VSS64  = GND
  DQ2_A  = M_F_CPU0_SA_DQ<2>
  VSS65  = GND
  DQ3_A  = M_F_CPU0_SA_DQ<3>
  VSS66  = GND
  \dqs5_a_c||tdqs5_a_c||dqs5_a_t||tdqs5_a_t\  = M_F_CPU0_SA_DQS_DN<5>
  \dqs5_a_t||tdqs5_a_t\  = M_F_CPU0_SA_DQS_DP<5>
  VSS67  = GND
  DQ6_A  = M_F_CPU0_SA_DQ<6>
  VSS68  = GND
  DQ7_A  = M_F_CPU0_SA_DQ<7>
  VSS69  = GND
  DQ10_A  = M_F_CPU0_SA_DQ<10>
  VSS70  = GND
  DQ11_A  = M_F_CPU0_SA_DQ<11>
  VSS71  = GND
  \dqs6_a_c||tdqs6_a_c||dqs6_a_t||tdqs6_a_t\  = M_F_CPU0_SA_DQS_DN<6>
  \dqs6_a_t||tdqs6_a_t\  = M_F_CPU0_SA_DQS_DP<6>
  VSS72  = GND
  DQ14_A  = M_F_CPU0_SA_DQ<14>
  VSS73  = GND
  DQ15_A  = M_F_CPU0_SA_DQ<15>
  VSS74  = GND
  DQ18_A  = M_F_CPU0_SA_DQ<18>
  VSS75  = GND
  DQ19_A  = M_F_CPU0_SA_DQ<19>
  VSS76  = GND
  \dqs7_a_c||tdqs7_a_c\  = M_F_CPU0_SA_DQS_DN<7>
  \dqs7_a_t||tdqs7_a_t\  = M_F_CPU0_SA_DQS_DP<7>
  VSS77  = GND
  DQ22_A  = M_F_CPU0_SA_DQ<22>
  VSS78  = GND
  DQ23_A  = M_F_CPU0_SA_DQ<23>
  VSS79  = GND
  DQ26_A  = M_F_CPU0_SA_DQ<26>
  VSS80  = GND
  DQ27_A  = M_F_CPU0_SA_DQ<27>
  VSS81  = GND
  \dqs8_a_c||tdqs8_a_c\  = M_F_CPU0_SA_DQS_DN<8>
  \dqs8_a_t||tdqs8_a_t\  = M_F_CPU0_SA_DQS_DP<8>
  VSS82  = GND
  DQ30_A  = M_F_CPU0_SA_DQ<30>
  VSS83  = GND
  DQ31_A  = M_F_CPU0_SA_DQ<31>
  VSS84  = GND
  CB2_A  = M_F_CPU0_SA_CB<2>
  VSS85  = GND
  CB3_A  = M_F_CPU0_SA_CB<3>
  VSS86  = GND
  \dqs9_a_c||tdqs9_a_c\  = M_F_CPU0_SA_DQS_DN<9>
  \dqs9_a_t||tdqs9_a_t\  = M_F_CPU0_SA_DQS_DP<9>
  VSS87  = GND
  CB6_A  = M_F_CPU0_SA_CB<6>
  VSS88  = GND
  CB7_A  = M_F_CPU0_SA_CB<7>
  VSS89  = GND
  RESET_N  = RST_M_EF_CPU0_FPGA_N
  VSS90  = GND
  CS1_A_N  = M_F_CPU0_SA_CS_N<3>
  VSS91  = GND
  CA1_A  = M_F_CPU0_SA_CA<1>
  VSS92  = GND
  CA3_A  = M_F_CPU0_SA_CA<3>
  VSS93  = GND
  CA5_A  = M_F_CPU0_SA_CA<5>
  VSS94  = GND
  CK_T  = M_F_CPU0_CLK_DP<1>
  CK_C  = M_F_CPU0_CLK_DN<1>
  VSS95  = GND
  RFU4  = TP_CHF_CPU0_DIMM2_FRU_4
  CA1_B  = M_F_CPU0_SB_CA<1>
  VSS96  = GND
  CA3_B  = M_F_CPU0_SB_CA<3>
  VSS97  = GND
  CA5_B  = M_F_CPU0_SB_CA<5>
  VSS98  = GND
  PAR_B  = M_F_CPU0_SB_PAR
  VSS99  = GND
  CS1_B_N  = M_F_CPU0_SB_CS_N<3>
  VSS100  = GND
  RFU5  = TP_CHF_CPU0_DIMM2_FRU_5
  RFU6  = TP_CHF_CPU0_DIMM2_FRU_6
  VSS101  = GND
  CB6_B  = M_F_CPU0_SB_CB<6>
  VSS102  = GND
  CB7_B  = M_F_CPU0_SB_CB<7>
  VSS103  = GND
  DQS4_B_C  = M_F_CPU0_SB_DQS_DN<4>
  DQS4_B_T  = M_F_CPU0_SB_DQS_DP<4>
  VSS104  = GND
  CB2_B  = M_F_CPU0_SB_CB<2>
  VSS105  = GND
  CB3_B  = M_F_CPU0_SB_CB<3>
  VSS106  = GND
  DQ2_B  = M_F_CPU0_SB_DQ<2>
  VSS107  = GND
  DQ3_B  = M_F_CPU0_SB_DQ<3>
  VSS108  = GND
  \dqs5_b_c||tdqs5_b_c\  = M_F_CPU0_SB_DQS_DN<5>
  \dqs5_b_t||tdqs5_b_t\  = M_F_CPU0_SB_DQS_DP<5>
  VSS109  = GND
  DQ6_B  = M_F_CPU0_SB_DQ<6>
  VSS110  = GND
  DQ7_B  = M_F_CPU0_SB_DQ<7>
  VSS111  = GND
  DQ10_B  = M_F_CPU0_SB_DQ<10>
  VSS112  = GND
  DQ11_B  = M_F_CPU0_SB_DQ<11>
  VSS113  = GND
  \dqs6_b_c||tdqs6_b_c\  = M_F_CPU0_SB_DQS_DN<6>
  \dqs6_b_t||tdqs6_b_t\  = M_F_CPU0_SB_DQS_DP<6>
  VSS114  = GND
  DQ14_B  = M_F_CPU0_SB_DQ<14>
  VSS115  = GND
  DQ15_B  = M_F_CPU0_SB_DQ<15>
  VSS116  = GND
  DQ18_B  = M_F_CPU0_SB_DQ<18>
  VSS117  = GND
  DQ19_B  = M_F_CPU0_SB_DQ<19>
  VSS118  = GND
  \dqs7_b_c||tdqs7_b_c\  = M_F_CPU0_SB_DQS_DN<7>
  \dqs7_b_t||tdqs7_b_t\  = M_F_CPU0_SB_DQS_DP<7>
  VSS119  = GND
  DQ22_B  = M_F_CPU0_SB_DQ<22>
  VSS120  = GND
  DQ23_B  = M_F_CPU0_SB_DQ<23>
  VSS121  = GND
  DQ26_B  = M_F_CPU0_SB_DQ<26>
  VSS122  = GND
  DQ27_B  = M_F_CPU0_SB_DQ<27>
  VSS123  = GND
  \dqs8_b_c||tdqs8_b_c\  = M_F_CPU0_SB_DQS_DN<8>
  \dqs8_b_t||tdqs8_b_t\  = M_F_CPU0_SB_DQS_DP<8>
  VSS124  = GND
  DQ30_B  = M_F_CPU0_SB_DQ<30>
  VSS125  = GND
  DQ31_B  = M_F_CPU0_SB_DQ<31>
  VSS126  = GND
  G1  = GND
  G2  = GND
  G3  = GND

(kicad_pcb
	(version 20260206)
	(generator "pcbnew")
	(generator_version "10.0")
	(general
		(thickness 1.6)
		(legacy_teardrops no)
	)
	(paper "A4")
	(title_block
		(title "03242023_DA0F0TMBIJ0_F0T_Motherboard_J_brd_V01_OCP.brd")
		(comment 1 "Grand Teton / footprint 3198 of 6105 (J12), pads 229-274 of 291")
	)
	(layers
		(0 "F.Cu" signal "TOP")
		(4 "In1.Cu" signal "GND")
		(6 "In2.Cu" signal "IN1")
		(8 "In3.Cu" signal "GND1")
		(10 "In4.Cu" signal "IN2")
		(12 "In5.Cu" signal "GND2")
		(14 "In6.Cu" signal "IN3")
		(16 "In7.Cu" signal "GND3")
		(18 "In8.Cu" signal "VCC")
		(20 "In9.Cu" signal "VCC1")
		(22 "In10.Cu" signal "GND4")
		(24 "In11.Cu" signal "IN4")
		(26 "In12.Cu" signal "GND5")
		(28 "In13.Cu" signal "IN5")
		(30 "In14.Cu" signal "GND6")
		(32 "In15.Cu" signal "IN6")
		(34 "In16.Cu" signal "GND7")
		(2 "B.Cu" signal "BOTTOM")
		(9 "F.Adhes" user "F.Adhesive")
		(11 "B.Adhes" user "B.Adhesive")
		(13 "F.Paste" user "Package Geometry/Pastemask Top")
		(15 "B.Paste" user "Package Geometry/Pastemask Bottom")
		(5 "F.SilkS" user "Ref Des/Silkscreen Top")
		(7 "B.SilkS" user "Ref Des/Silkscreen Bottom")
		(1 "F.Mask" user "Board Geometry/Soldermask Top")
		(3 "B.Mask" user "Board Geometry/Soldermask Bottom")
		(17 "Dwgs.User" user "User.Drawings")
		(19 "Cmts.User" user "User.Comments")
		(21 "Eco1.User" user "User.Eco1")
		(23 "Eco2.User" user "User.Eco2")
		(25 "Edge.Cuts" user "Board Geometry/Outline")
		(27 "Margin" user)
		(31 "F.CrtYd" user "Package Geometry/Place Bound Top")
		(29 "B.CrtYd" user "Package Geometry/Place Bound Bottom")
		(35 "F.Fab" user "Ref Des/Assembly Top")
		(33 "B.Fab" user "Ref Des/Assembly Bottom")
	)
	(footprint ""
		(layer "F.Cu")
		(at 423.890948 -258.091686)
		(property "Reference" "J12"
			(at -3.683 -81.702148 0)
			(unlocked yes)
			(layer "F.SilkS")
			(effects
				(font
					(size 0.7874 0.5842)
					(thickness 0.1524)
				)
				(justify left)
			)
		)
		(property "Value" ""
			(at 0 0 0)
			(layer "F.Fab")
			(effects
				(font
					(size 1.27 1.27)
				)
			)
		)
		(duplicate_pad_numbers_are_jumpers no)
		(pad "229" smd rect
			(at 2.050034 13.17498 270)
			(size 0.519938 1.4986)
			(layers "F.Cu" "F.Mask" "F.Paste")
			(net "M_F_CPU0_SB_CS_N<3>")
		)
		(pad "230" smd rect
			(at 2.050034 14.025118 270)
			(size 0.519938 1.4986)
			(layers "F.Cu" "F.Mask" "F.Paste")
			(net "GND")
		)
		(pad "231" smd rect
			(at 2.050034 14.875002 270)
			(size 0.519938 1.4986)
			(layers "F.Cu" "F.Mask" "F.Paste")
			(net "TP_CHF_CPU0_DIMM2_FRU_5")
		)
		(pad "232" smd rect
			(at 2.050034 15.724886 270)
			(size 0.519938 1.4986)
			(layers "F.Cu" "F.Mask" "F.Paste")
			(net "TP_CHF_CPU0_DIMM2_FRU_6")
		)
		(pad "233" smd rect
			(at 2.050034 16.575024 270)
			(size 0.519938 1.4986)
			(layers "F.Cu" "F.Mask" "F.Paste")
			(net "GND")
		)
		(pad "234" smd rect
			(at 2.050034 17.424908 270)
			(size 0.519938 1.4986)
			(layers "F.Cu" "F.Mask" "F.Paste")
			(net "M_F_CPU0_SB_CB<6>")
		)
		(pad "235" smd rect
			(at 2.050034 18.275046 270)
			(size 0.519938 1.4986)
			(layers "F.Cu" "F.Mask" "F.Paste")
			(net "GND")
		)
		(pad "236" smd rect
			(at 2.050034 19.12493 270)
			(size 0.519938 1.4986)
			(layers "F.Cu" "F.Mask" "F.Paste")
			(net "M_F_CPU0_SB_CB<7>")
		)
		(pad "237" smd rect
			(at 2.050034 19.975068 270)
			(size 0.519938 1.4986)
			(layers "F.Cu" "F.Mask" "F.Paste")
			(net "GND")
		)
		(pad "238" smd rect
			(at 2.050034 20.824952 270)
			(size 0.519938 1.4986)
			(layers "F.Cu" "F.Mask" "F.Paste")
			(net "M_F_CPU0_SB_DQS_DN<4>")
		)
		(pad "239" smd rect
			(at 2.050034 21.67509 270)
			(size 0.519938 1.4986)
			(layers "F.Cu" "F.Mask" "F.Paste")
			(net "M_F_CPU0_SB_DQS_DP<4>")
		)
		(pad "240" smd rect
			(at 2.050034 22.524974 270)
			(size 0.519938 1.4986)
			(layers "F.Cu" "F.Mask" "F.Paste")
			(net "GND")
		)
		(pad "241" smd rect
			(at 2.050034 23.375112 270)
			(size 0.519938 1.4986)
			(layers "F.Cu" "F.Mask" "F.Paste")
			(net "M_F_CPU0_SB_CB<2>")
		)
		(pad "242" smd rect
			(at 2.050034 24.224996 270)
			(size 0.519938 1.4986)
			(layers "F.Cu" "F.Mask" "F.Paste")
			(net "GND")
		)
		(pad "243" smd rect
			(at 2.050034 25.07488 270)
			(size 0.519938 1.4986)
			(layers "F.Cu" "F.Mask" "F.Paste")
			(net "M_F_CPU0_SB_CB<3>")
		)
		(pad "244" smd rect
			(at 2.050034 25.925018 270)
			(size 0.519938 1.4986)
			(layers "F.Cu" "F.Mask" "F.Paste")
			(net "GND")
		)
		(pad "245" smd rect
			(at 2.050034 26.774902 270)
			(size 0.519938 1.4986)
			(layers "F.Cu" "F.Mask" "F.Paste")
			(net "M_F_CPU0_SB_DQ<2>")
		)
		(pad "246" smd rect
			(at 2.050034 27.62504 270)
			(size 0.519938 1.4986)
			(layers "F.Cu" "F.Mask" "F.Paste")
			(net "GND")
		)
		(pad "247" smd rect
			(at 2.050034 28.474924 270)
			(size 0.519938 1.4986)
			(layers "F.Cu" "F.Mask" "F.Paste")
			(net "M_F_CPU0_SB_DQ<3>")
		)
		(pad "248" smd rect
			(at 2.050034 29.325062 270)
			(size 0.519938 1.4986)
			(layers "F.Cu" "F.Mask" "F.Paste")
			(net "GND")
		)
		(pad "249" smd rect
			(at 2.050034 30.174946 270)
			(size 0.519938 1.4986)
			(layers "F.Cu" "F.Mask" "F.Paste")
			(net "M_F_CPU0_SB_DQS_DN<5>")
		)
		(pad "250" smd rect
			(at 2.050034 31.025084 270)
			(size 0.519938 1.4986)
			(layers "F.Cu" "F.Mask" "F.Paste")
			(net "M_F_CPU0_SB_DQS_DP<5>")
		)
		(pad "251" smd rect
			(at 2.050034 31.874968 270)
			(size 0.519938 1.4986)
			(layers "F.Cu" "F.Mask" "F.Paste")
			(net "GND")
		)
		(pad "252" smd rect
			(at 2.050034 32.725106 270)
			(size 0.519938 1.4986)
			(layers "F.Cu" "F.Mask" "F.Paste")
			(net "M_F_CPU0_SB_DQ<6>")
		)
		(pad "253" smd rect
			(at 2.050034 33.57499 270)
			(size 0.519938 1.4986)
			(layers "F.Cu" "F.Mask" "F.Paste")
			(net "GND")
		)
		(pad "254" smd rect
			(at 2.050034 34.425128 270)
			(size 0.519938 1.4986)
			(layers "F.Cu" "F.Mask" "F.Paste")
			(net "M_F_CPU0_SB_DQ<7>")
		)
		(pad "255" smd rect
			(at 2.050034 35.275012 270)
			(size 0.519938 1.4986)
			(layers "F.Cu" "F.Mask" "F.Paste")
			(net "GND")
		)
		(pad "256" smd rect
			(at 2.050034 36.124896 270)
			(size 0.519938 1.4986)
			(layers "F.Cu" "F.Mask" "F.Paste")
			(net "M_F_CPU0_SB_DQ<10>")
		)
		(pad "257" smd rect
			(at 2.050034 36.975034 270)
			(size 0.519938 1.4986)
			(layers "F.Cu" "F.Mask" "F.Paste")
			(net "GND")
		)
		(pad "258" smd rect
			(at 2.050034 37.824918 270)
			(size 0.519938 1.4986)
			(layers "F.Cu" "F.Mask" "F.Paste")
			(net "M_F_CPU0_SB_DQ<11>")
		)
		(pad "259" smd rect
			(at 2.050034 38.675056 270)
			(size 0.519938 1.4986)
			(layers "F.Cu" "F.Mask" "F.Paste")
			(net "GND")
		)
		(pad "260" smd rect
			(at 2.050034 39.52494 270)
			(size 0.519938 1.4986)
			(layers "F.Cu" "F.Mask" "F.Paste")
			(net "M_F_CPU0_SB_DQS_DN<6>")
		)
		(pad "261" smd rect
			(at 2.050034 40.375078 270)
			(size 0.519938 1.4986)
			(layers "F.Cu" "F.Mask" "F.Paste")
			(net "M_F_CPU0_SB_DQS_DP<6>")
		)
		(pad "262" smd rect
			(at 2.050034 41.224962 270)
			(size 0.519938 1.4986)
			(layers "F.Cu" "F.Mask" "F.Paste")
			(net "GND")
		)
		(pad "263" smd rect
			(at 2.050034 42.0751 270)
			(size 0.519938 1.4986)
			(layers "F.Cu" "F.Mask" "F.Paste")
			(net "M_F_CPU0_SB_DQ<14>")
		)
		(pad "264" smd rect
			(at 2.050034 42.924984 270)
			(size 0.519938 1.4986)
			(layers "F.Cu" "F.Mask" "F.Paste")
			(net "GND")
		)
		(pad "265" smd rect
			(at 2.050034 43.775122 270)
			(size 0.519938 1.4986)
			(layers "F.Cu" "F.Mask" "F.Paste")
			(net "M_F_CPU0_SB_DQ<15>")
		)
		(pad "266" smd rect
			(at 2.050034 44.625006 270)
			(size 0.519938 1.4986)
			(layers "F.Cu" "F.Mask" "F.Paste")
			(net "GND")
		)
		(pad "267" smd rect
			(at 2.050034 45.47489 270)
			(size 0.519938 1.4986)
			(layers "F.Cu" "F.Mask" "F.Paste")
			(net "M_F_CPU0_SB_DQ<18>")
		)
		(pad "268" smd rect
			(at 2.050034 46.325028 270)
			(size 0.519938 1.4986)
			(layers "F.Cu" "F.Mask" "F.Paste")
			(net "GND")
		)
		(pad "269" smd rect
			(at 2.050034 47.174912 270)
			(size 0.519938 1.4986)
			(layers "F.Cu" "F.Mask" "F.Paste")
			(net "M_F_CPU0_SB_DQ<19>")
		)
		(pad "270" smd rect
			(at 2.050034 48.02505 270)
			(size 0.519938 1.4986)
			(layers "F.Cu" "F.Mask" "F.Paste")
			(net "GND")
		)
		(pad "271" smd rect
			(at 2.050034 48.874934 270)
			(size 0.519938 1.4986)
			(layers "F.Cu" "F.Mask" "F.Paste")
			(net "M_F_CPU0_SB_DQS_DN<7>")
		)
		(pad "272" smd rect
			(at 2.050034 49.725072 270)
			(size 0.519938 1.4986)
			(layers "F.Cu" "F.Mask" "F.Paste")
			(net "M_F_CPU0_SB_DQS_DP<7>")
		)
		(pad "273" smd rect
			(at 2.050034 50.574956 270)
			(size 0.519938 1.4986)
			(layers "F.Cu" "F.Mask" "F.Paste")
			(net "GND")
		)
		(pad "274" smd rect
			(at 2.050034 51.425094 270)
			(size 0.519938 1.4986)
			(layers "F.Cu" "F.Mask" "F.Paste")
			(net "M_F_CPU0_SB_DQ<22>")
		)
	)
)
